# S9S_MB_2U (Grand Teton) — schematic netlist excerpt (pin names and nets, part order shuffled) for the footprints in the layout excerpt that follows; sources: Cadence DE-HDL packaged netlist, KiCad conversion of 03242023_DA0F0TMBIJ0_F0T_Motherboard_J_brd_V01_OCP.brd

R147  Q_RES  10K 1% CHIP  pkg 0402LF  page 197 : A = PECI_PCH_R ; B = GND
R2407  Q_RES  10K 1% CHIP  pkg 0402LF  page 281 : A = P3V3_AUX ; B = PWRGD_PVPP_HBM_CPU0_R

(kicad_pcb
	(version 20260206)
	(generator "pcbnew")
	(generator_version "10.0")
	(general
		(thickness 1.6)
		(legacy_teardrops no)
	)
	(paper "A4")
	(title_block
		(title "03242023_DA0F0TMBIJ0_F0T_Motherboard_J_brd_V01_OCP.brd")
		(comment 1 "Grand Teton / footprints 4077-4078 of 6105")
	)
	(layers
		(0 "F.Cu" signal "TOP")
		(4 "In1.Cu" signal "GND")
		(6 "In2.Cu" signal "IN1")
		(8 "In3.Cu" signal "GND1")
		(10 "In4.Cu" signal "IN2")
		(12 "In5.Cu" signal "GND2")
		(14 "In6.Cu" signal "IN3")
		(16 "In7.Cu" signal "GND3")
		(18 "In8.Cu" signal "VCC")
		(20 "In9.Cu" signal "VCC1")
		(22 "In10.Cu" signal "GND4")
		(24 "In11.Cu" signal "IN4")
		(26 "In12.Cu" signal "GND5")
		(28 "In13.Cu" signal "IN5")
		(30 "In14.Cu" signal "GND6")
		(32 "In15.Cu" signal "IN6")
		(34 "In16.Cu" signal "GND7")
		(2 "B.Cu" signal "BOTTOM")
		(9 "F.Adhes" user "F.Adhesive")
		(11 "B.Adhes" user "B.Adhesive")
		(13 "F.Paste" user "Package Geometry/Pastemask Top")
		(15 "B.Paste" user "Package Geometry/Pastemask Bottom")
		(5 "F.SilkS" user "Ref Des/Silkscreen Top")
		(7 "B.SilkS" user "Ref Des/Silkscreen Bottom")
		(1 "F.Mask" user "Board Geometry/Soldermask Top")
		(3 "B.Mask" user "Board Geometry/Soldermask Bottom")
		(17 "Dwgs.User" user "User.Drawings")
		(19 "Cmts.User" user "User.Comments")
		(21 "Eco1.User" user "User.Eco1")
		(23 "Eco2.User" user "User.Eco2")
		(25 "Edge.Cuts" user "Board Geometry/Outline")
		(27 "Margin" user)
		(31 "F.CrtYd" user "Package Geometry/Place Bound Top")
		(29 "B.CrtYd" user "Package Geometry/Place Bound Bottom")
		(35 "F.Fab" user "Ref Des/Assembly Top")
		(33 "B.Fab" user "Ref Des/Assembly Bottom")
	)
	(footprint ""
		(layer "F.Cu")
		(at 309.01894 -56.045608 90)
		(property "Reference" "R147"
			(at 0 0 90)
			(layer "F.SilkS")
			(hide yes)
			(effects
				(font
					(size 1.27 1.27)
				)
			)
		)
		(property "Value" ""
			(at 0 0 90)
			(layer "F.Fab")
			(effects
				(font
					(size 1.27 1.27)
				)
			)
		)
		(duplicate_pad_numbers_are_jumpers no)
		(fp_line
			(start 0.7874 -0.4064)
			(end 0.7874 0.4064)
			(stroke
				(width 0.1524)
				(type default)
			)
			(layer "F.SilkS")
		)
		(fp_line
			(start -0.7874 -0.4064)
			(end 0.7874 -0.4064)
			(stroke
				(width 0.1524)
				(type default)
			)
			(layer "F.SilkS")
		)
		(fp_line
			(start 0.7874 0.4064)
			(end -0.7874 0.4064)
			(stroke
				(width 0.1524)
				(type default)
			)
			(layer "F.SilkS")
		)
		(fp_line
			(start -0.7874 0.4064)
			(end -0.7874 -0.4064)
			(stroke
				(width 0.1524)
				(type default)
			)
			(layer "F.SilkS")
		)
		(fp_line
			(start -0.12065 -0.305054)
			(end -0.12065 -0.2794)
			(stroke
				(width 0.1)
				(type default)
			)
			(layer "F.Fab")
		)
		(fp_line
			(start -0.67945 -0.305054)
			(end -0.12065 -0.305054)
			(stroke
				(width 0.1)
				(type default)
			)
			(layer "F.Fab")
		)
		(fp_line
			(start 0.67945 -0.3048)
			(end 0.67945 0.3048)
			(stroke
				(width 0.1)
				(type default)
			)
			(layer "F.Fab")
		)
		(fp_line
			(start 0.12065 -0.3048)
			(end 0.67945 -0.3048)
			(stroke
				(width 0.1)
				(type default)
			)
			(layer "F.Fab")
		)
		(fp_line
			(start 0.12065 -0.2794)
			(end 0.12065 -0.3048)
			(stroke
				(width 0.1)
				(type default)
			)
			(layer "F.Fab")
		)
		(fp_line
			(start -0.12065 -0.2794)
			(end 0.12065 -0.2794)
			(stroke
				(width 0.1)
				(type default)
			)
			(layer "F.Fab")
		)
		(fp_line
			(start 0.120396 0.2794)
			(end -0.12065 0.2794)
			(stroke
				(width 0.1)
				(type default)
			)
			(layer "F.Fab")
		)
		(fp_line
			(start -0.12065 0.2794)
			(end -0.12065 0.3048)
			(stroke
				(width 0.1)
				(type default)
			)
			(layer "F.Fab")
		)
		(fp_line
			(start 0.67945 0.3048)
			(end 0.120396 0.3048)
			(stroke
				(width 0.1)
				(type default)
			)
			(layer "F.Fab")
		)
		(fp_line
			(start 0.120396 0.3048)
			(end 0.120396 0.2794)
			(stroke
				(width 0.1)
				(type default)
			)
			(layer "F.Fab")
		)
		(fp_line
			(start -0.12065 0.3048)
			(end -0.67945 0.3048)
			(stroke
				(width 0.1)
				(type default)
			)
			(layer "F.Fab")
		)
		(fp_line
			(start -0.67945 0.3048)
			(end -0.67945 -0.305054)
			(stroke
				(width 0.1)
				(type default)
			)
			(layer "F.Fab")
		)
		(pad "1" smd circle
			(at -0.40005 0 90)
			(size 0 0)
			(layers "F.Cu" "F.Mask" "F.Paste")
			(net "PECI_PCH_R")
		)
		(pad "2" smd circle
			(at 0.40005 0 90)
			(size 0 0)
			(layers "F.Cu" "F.Mask" "F.Paste")
			(net "GND")
		)
	)
	(footprint ""
		(layer "F.Cu")
		(at 369.724178 -355.69779)
		(property "Reference" "R2407"
			(at 0 0 0)
			(layer "F.SilkS")
			(hide yes)
			(effects
				(font
					(size 1.27 1.27)
				)
			)
		)
		(property "Value" ""
			(at 0 0 0)
			(layer "F.Fab")
			(effects
				(font
					(size 1.27 1.27)
				)
			)
		)
		(duplicate_pad_numbers_are_jumpers no)
		(fp_line
			(start -0.7874 -0.4064)
			(end 0.7874 -0.4064)
			(stroke
				(width 0.1524)
				(type default)
			)
			(layer "F.SilkS")
		)
		(fp_line
			(start -0.7874 0.4064)
			(end -0.7874 -0.4064)
			(stroke
				(width 0.1524)
				(type default)
			)
			(layer "F.SilkS")
		)
		(fp_line
			(start 0.7874 -0.4064)
			(end 0.7874 0.4064)
			(stroke
				(width 0.1524)
				(type default)
			)
			(layer "F.SilkS")
		)
		(fp_line
			(start 0.7874 0.4064)
			(end -0.7874 0.4064)
			(stroke
				(width 0.1524)
				(type default)
			)
			(layer "F.SilkS")
		)
		(fp_line
			(start -0.67945 -0.305054)
			(end -0.12065 -0.305054)
			(stroke
				(width 0.1)
				(type default)
			)
			(layer "F.Fab")
		)
		(fp_line
			(start -0.67945 0.3048)
			(end -0.67945 -0.305054)
			(stroke
				(width 0.1)
				(type default)
			)
			(layer "F.Fab")
		)
		(fp_line
			(start -0.12065 -0.305054)
			(end -0.12065 -0.2794)
			(stroke
				(width 0.1)
				(type default)
			)
			(layer "F.Fab")
		)
		(fp_line
			(start -0.12065 -0.2794)
			(end 0.12065 -0.2794)
			(stroke
				(width 0.1)
				(type default)
			)
			(layer "F.Fab")
		)
		(fp_line
			(start -0.12065 0.2794)
			(end -0.12065 0.3048)
			(stroke
				(width 0.1)
				(type default)
			)
			(layer "F.Fab")
		)
		(fp_line
			(start -0.12065 0.3048)
			(end -0.67945 0.3048)
			(stroke
				(width 0.1)
				(type default)
			)
			(layer "F.Fab")
		)
		(fp_line
			(start 0.120396 0.2794)
			(end -0.12065 0.2794)
			(stroke
				(width 0.1)
				(type default)
			)
			(layer "F.Fab")
		)
		(fp_line
			(start 0.120396 0.3048)
			(end 0.120396 0.2794)
			(stroke
				(width 0.1)
				(type default)
			)
			(layer "F.Fab")
		)
		(fp_line
			(start 0.12065 -0.3048)
			(end 0.67945 -0.3048)
			(stroke
				(width 0.1)
				(type default)
			)
			(layer "F.Fab")
		)
		(fp_line
			(start 0.12065 -0.2794)
			(end 0.12065 -0.3048)
			(stroke
				(width 0.1)
				(type default)
			)
			(layer "F.Fab")
		)
		(fp_line
			(start 0.67945 -0.3048)
			(end 0.67945 0.3048)
			(stroke
				(width 0.1)
				(type default)
			)
			(layer "F.Fab")
		)
		(fp_line
			(start 0.67945 0.3048)
			(end 0.120396 0.3048)
			(stroke
				(width 0.1)
				(type default)
			)
			(layer "F.Fab")
		)
		(pad "1" smd circle
			(at -0.40005 0)
			(size 0 0)
			(layers "F.Cu" "F.Mask" "F.Paste")
			(net "P3V3_AUX")
		)
		(pad "2" smd circle
			(at 0.40005 0)
			(size 0 0)
			(layers "F.Cu" "F.Mask" "F.Paste")
			(net "PWRGD_PVPP_HBM_CPU0_R")
		)
	)
)
